(kicad_pcb
	(version 20260206)
	(generator "pcbnew")
	(generator_version "10.0")
	(general
		(thickness 1.6)
		(legacy_teardrops no)
	)
	(paper "A4")
	(title_block
		(title "01162023_DA0F0TEBIF0_F0T_Expander_BD_F_brd_V02_OCP.brd")
		(comment 1 "Grand Teton / footprints 2614-2622 of 9728")
	)
	(layers
		(0 "F.Cu" signal "TOP")
		(4 "In1.Cu" signal "GND")
		(6 "In2.Cu" signal "VCC")
		(8 "In3.Cu" signal "VCC1")
		(10 "In4.Cu" signal "GND1")
		(12 "In5.Cu" signal "IN1")
		(14 "In6.Cu" signal "GND2")
		(16 "In7.Cu" signal "IN2")
		(18 "In8.Cu" signal "GND3")
		(20 "In9.Cu" signal "IN3")
		(22 "In10.Cu" signal "GND4")
		(24 "In11.Cu" signal "IN4")
		(26 "In12.Cu" signal "GND5")
		(28 "In13.Cu" signal "IN5")
		(30 "In14.Cu" signal "GND6")
		(32 "In15.Cu" signal "IN6")
		(34 "In16.Cu" signal "GND7")
		(2 "B.Cu" signal "BOTTOM")
		(9 "F.Adhes" user "F.Adhesive")
		(11 "B.Adhes" user "B.Adhesive")
		(13 "F.Paste" user "Package Geometry/Pastemask Top")
		(15 "B.Paste" user "Package Geometry/Pastemask Bottom")
		(5 "F.SilkS" user "Ref Des/Silkscreen Top")
		(7 "B.SilkS" user "Ref Des/Silkscreen Bottom")
		(1 "F.Mask" user "Board Geometry/Soldermask Top")
		(3 "B.Mask" user "Board Geometry/Soldermask Bottom")
		(17 "Dwgs.User" user "User.Drawings")
		(19 "Cmts.User" user "User.Comments")
		(21 "Eco1.User" user "User.Eco1")
		(23 "Eco2.User" user "User.Eco2")
		(25 "Edge.Cuts" user "Board Geometry/Outline")
		(27 "Margin" user)
		(31 "F.CrtYd" user "Package Geometry/Place Bound Top")
		(29 "B.CrtYd" user "Package Geometry/Place Bound Bottom")
		(35 "F.Fab" user "Ref Des/Assembly Top")
		(33 "B.Fab" user "Ref Des/Assembly Bottom")
	)
	(footprint ""
		(layer "F.Cu")
		(at 316.701932 -141.150848 -90)
		(property "Reference" "U34"
			(at 2.671318 0.014732 0)
			(unlocked yes)
			(layer "F.SilkS")
			(effects
				(font
					(size 0.7874 0.5842)
					(thickness 0.1524)
				)
			)
		)
		(property "Value" ""
			(at 0 0 270)
			(layer "F.Fab")
			(effects
				(font
					(size 1.27 1.27)
				)
			)
		)
		(duplicate_pad_numbers_are_jumpers no)
		(fp_line
			(start -1.949958 1.610106)
			(end -1.949958 -1.610106)
			(stroke
				(width 0.1524)
				(type default)
			)
			(layer "F.SilkS")
		)
		(fp_line
			(start 1.949958 1.610106)
			(end -1.949958 1.610106)
			(stroke
				(width 0.1524)
				(type default)
			)
			(layer "F.SilkS")
		)
		(fp_line
			(start 1.949958 -1.560068)
			(end 1.949958 1.610106)
			(stroke
				(width 0.1524)
				(type default)
			)
			(layer "F.SilkS")
		)
		(fp_line
			(start -1.949958 -1.610106)
			(end 1.949958 -1.610106)
			(stroke
				(width 0.1524)
				(type default)
			)
			(layer "F.SilkS")
		)
		(fp_line
			(start -0.750062 1.560068)
			(end -0.750062 -1.560068)
			(stroke
				(width 0.1)
				(type default)
			)
			(layer "F.Fab")
		)
		(fp_line
			(start 0.750062 1.560068)
			(end -0.750062 1.560068)
			(stroke
				(width 0.1)
				(type default)
			)
			(layer "F.Fab")
		)
		(fp_line
			(start -0.750062 -1.560068)
			(end 0.750062 -1.560068)
			(stroke
				(width 0.1)
				(type default)
			)
			(layer "F.Fab")
		)
		(fp_line
			(start 0.750062 -1.560068)
			(end 0.750062 1.560068)
			(stroke
				(width 0.1)
				(type default)
			)
			(layer "F.Fab")
		)
		(pad "D" smd rect
			(at 1.100074 0 180)
			(size 1.016 1.4224)
			(layers "F.Cu" "F.Mask" "F.Paste")
			(net "HP_NIC5_EN")
		)
		(pad "G" smd rect
			(at -1.100074 -0.94996 180)
			(size 1.016 1.4224)
			(layers "F.Cu" "F.Mask" "F.Paste")
			(net "PRSNT_NIC5_R_N")
		)
		(pad "S" smd rect
			(at -1.100074 0.94996 180)
			(size 1.016 1.4224)
			(layers "F.Cu" "F.Mask" "F.Paste")
			(net "GND")
		)
	)
	(footprint ""
		(layer "F.Cu")
		(at 216.437718 -251.163836 -90)
		(property "Reference" "C4287"
			(at 0 0 270)
			(layer "F.SilkS")
			(hide yes)
			(effects
				(font
					(size 1.27 1.27)
				)
			)
		)
		(property "Value" ""
			(at 0 0 270)
			(layer "F.Fab")
			(effects
				(font
					(size 1.27 1.27)
				)
			)
		)
		(duplicate_pad_numbers_are_jumpers no)
		(fp_line
			(start -1.524 0.762)
			(end -1.524 -0.762)
			(stroke
				(width 0.1524)
				(type default)
			)
			(layer "F.SilkS")
		)
		(fp_line
			(start 1.524 0.762)
			(end -1.524 0.762)
			(stroke
				(width 0.1524)
				(type default)
			)
			(layer "F.SilkS")
		)
		(fp_line
			(start -1.524 -0.762)
			(end 1.524 -0.762)
			(stroke
				(width 0.1524)
				(type default)
			)
			(layer "F.SilkS")
		)
		(fp_line
			(start 1.524 -0.762)
			(end 1.524 0.762)
			(stroke
				(width 0.1524)
				(type default)
			)
			(layer "F.SilkS")
		)
		(fp_line
			(start -1.1049 0.724916)
			(end 1.1049 0.724916)
			(stroke
				(width 0.1)
				(type default)
			)
			(layer "F.Fab")
		)
		(fp_line
			(start 1.1049 0.724916)
			(end 1.1049 -0.724916)
			(stroke
				(width 0.1)
				(type default)
			)
			(layer "F.Fab")
		)
		(fp_line
			(start -1.1049 -0.724916)
			(end -1.1049 0.724916)
			(stroke
				(width 0.1)
				(type default)
			)
			(layer "F.Fab")
		)
		(fp_line
			(start 1.1049 -0.724916)
			(end -1.1049 -0.724916)
			(stroke
				(width 0.1)
				(type default)
			)
			(layer "F.Fab")
		)
		(pad "1" smd rect
			(at -0.889 0 90)
			(size 1.016 1.27)
			(layers "F.Cu" "F.Mask" "F.Paste")
			(net "P1V25_SERDES_VDDPLL_PEX1_C5")
		)
		(pad "2" smd rect
			(at 0.889 0 90)
			(size 1.016 1.27)
			(layers "F.Cu" "F.Mask" "F.Paste")
			(net "GND")
		)
		(zone
			(layer "F.Cu")
			(hatch none 0.5)
			(connect_pads
				(clearance 0)
			)
			(min_thickness 0.25)
			(keepout
				(tracks not_allowed)
				(vias allowed)
				(pads allowed)
				(copperpour not_allowed)
				(footprints allowed)
			)
			(placement
				(enabled no)
				(sheetname "")
			)
			(fill
				(thermal_gap 0.5)
				(thermal_bridge_width 0.5)
				(island_removal_mode 0)
			)
			(polygon
				(pts
					(xy 217.162634 -251.494036) (xy 215.712802 -251.494036) (xy 215.712802 -250.833636) (xy 217.162634 -250.833636)
				)
			)
		)
	)
	(footprint ""
		(layer "F.Cu")
		(at 345.76131 -260.671564)
		(property "Reference" "PR140"
			(at 0 0 0)
			(layer "F.SilkS")
			(hide yes)
			(effects
				(font
					(size 1.27 1.27)
				)
			)
		)
		(property "Value" ""
			(at 0 0 0)
			(layer "F.Fab")
			(effects
				(font
					(size 1.27 1.27)
				)
			)
		)
		(duplicate_pad_numbers_are_jumpers no)
		(fp_line
			(start -0.7874 -0.4064)
			(end 0.7874 -0.4064)
			(stroke
				(width 0.1524)
				(type default)
			)
			(layer "F.SilkS")
		)
		(fp_line
			(start -0.7874 0.4064)
			(end -0.7874 -0.4064)
			(stroke
				(width 0.1524)
				(type default)
			)
			(layer "F.SilkS")
		)
		(fp_line
			(start 0.7874 -0.4064)
			(end 0.7874 0.4064)
			(stroke
				(width 0.1524)
				(type default)
			)
			(layer "F.SilkS")
		)
		(fp_line
			(start 0.7874 0.4064)
			(end -0.7874 0.4064)
			(stroke
				(width 0.1524)
				(type default)
			)
			(layer "F.SilkS")
		)
		(fp_line
			(start -0.67945 -0.305054)
			(end -0.12065 -0.305054)
			(stroke
				(width 0.1)
				(type default)
			)
			(layer "F.Fab")
		)
		(fp_line
			(start -0.67945 0.3048)
			(end -0.67945 -0.305054)
			(stroke
				(width 0.1)
				(type default)
			)
			(layer "F.Fab")
		)
		(fp_line
			(start -0.12065 -0.305054)
			(end -0.12065 -0.2794)
			(stroke
				(width 0.1)
				(type default)
			)
			(layer "F.Fab")
		)
		(fp_line
			(start -0.12065 -0.2794)
			(end 0.12065 -0.2794)
			(stroke
				(width 0.1)
				(type default)
			)
			(layer "F.Fab")
		)
		(fp_line
			(start -0.12065 0.2794)
			(end -0.12065 0.3048)
			(stroke
				(width 0.1)
				(type default)
			)
			(layer "F.Fab")
		)
		(fp_line
			(start -0.12065 0.3048)
			(end -0.67945 0.3048)
			(stroke
				(width 0.1)
				(type default)
			)
			(layer "F.Fab")
		)
		(fp_line
			(start 0.120396 0.2794)
			(end -0.12065 0.2794)
			(stroke
				(width 0.1)
				(type default)
			)
			(layer "F.Fab")
		)
		(fp_line
			(start 0.120396 0.3048)
			(end 0.120396 0.2794)
			(stroke
				(width 0.1)
				(type default)
			)
			(layer "F.Fab")
		)
		(fp_line
			(start 0.12065 -0.3048)
			(end 0.67945 -0.3048)
			(stroke
				(width 0.1)
				(type default)
			)
			(layer "F.Fab")
		)
		(fp_line
			(start 0.12065 -0.2794)
			(end 0.12065 -0.3048)
			(stroke
				(width 0.1)
				(type default)
			)
			(layer "F.Fab")
		)
		(fp_line
			(start 0.67945 -0.3048)
			(end 0.67945 0.3048)
			(stroke
				(width 0.1)
				(type default)
			)
			(layer "F.Fab")
		)
		(fp_line
			(start 0.67945 0.3048)
			(end 0.120396 0.3048)
			(stroke
				(width 0.1)
				(type default)
			)
			(layer "F.Fab")
		)
		(pad "1" smd circle
			(at -0.40005 0)
			(size 0 0)
			(layers "F.Cu" "F.Mask" "F.Paste")
			(net "P0V8_PEX2_VREF")
		)
		(pad "2" smd circle
			(at 0.40005 0)
			(size 0 0)
			(layers "F.Cu" "F.Mask" "F.Paste")
			(net "P0V8_PEX2_ADDR")
		)
	)
	(footprint ""
		(layer "F.Cu")
		(at 363.590078 -407.599896)
		(property "Reference" "H59"
			(at -3.877818 -5.352542 0)
			(unlocked yes)
			(layer "F.SilkS")
			(effects
				(font
					(size 0.7874 0.5842)
					(thickness 0.1524)
				)
				(justify left)
			)
		)
		(property "Value" ""
			(at 0 0 0)
			(layer "F.Fab")
			(effects
				(font
					(size 1.27 1.27)
				)
			)
		)
		(duplicate_pad_numbers_are_jumpers no)
		(pad "1" thru_hole circle
			(at 0 0)
			(size 10.0076 10.0076)
			(drill 5.6134)
			(layers "*.Cu" "*.Mask")
			(remove_unused_layers no)
			(net "GND")
			(clearance -1.9431)
		)
	)
	(footprint ""
		(layer "F.Cu")
		(at 303.938432 -44.341542 90)
		(property "Reference" "C329"
			(at 0 0 90)
			(layer "F.SilkS")
			(hide yes)
			(effects
				(font
					(size 1.27 1.27)
				)
			)
		)
		(property "Value" ""
			(at 0 0 90)
			(layer "F.Fab")
			(effects
				(font
					(size 1.27 1.27)
				)
			)
		)
		(duplicate_pad_numbers_are_jumpers no)
		(fp_line
			(start 0.7874 -0.4064)
			(end 0.7874 0.4064)
			(stroke
				(width 0.1524)
				(type default)
			)
			(layer "F.SilkS")
		)
		(fp_line
			(start -0.7874 -0.4064)
			(end 0.7874 -0.4064)
			(stroke
				(width 0.1524)
				(type default)
			)
			(layer "F.SilkS")
		)
		(fp_line
			(start 0.7874 0.4064)
			(end -0.7874 0.4064)
			(stroke
				(width 0.1524)
				(type default)
			)
			(layer "F.SilkS")
		)
		(fp_line
			(start -0.7874 0.4064)
			(end -0.7874 -0.4064)
			(stroke
				(width 0.1524)
				(type default)
			)
			(layer "F.SilkS")
		)
		(fp_line
			(start -0.12065 -0.305054)
			(end -0.12065 -0.2794)
			(stroke
				(width 0.1)
				(type default)
			)
			(layer "F.Fab")
		)
		(fp_line
			(start -0.67945 -0.305054)
			(end -0.12065 -0.305054)
			(stroke
				(width 0.1)
				(type default)
			)
			(layer "F.Fab")
		)
		(fp_line
			(start 0.67945 -0.3048)
			(end 0.67945 0.3048)
			(stroke
				(width 0.1)
				(type default)
			)
			(layer "F.Fab")
		)
		(fp_line
			(start 0.12065 -0.3048)
			(end 0.67945 -0.3048)
			(stroke
				(width 0.1)
				(type default)
			)
			(layer "F.Fab")
		)
		(fp_line
			(start 0.12065 -0.2794)
			(end 0.12065 -0.3048)
			(stroke
				(width 0.1)
				(type default)
			)
			(layer "F.Fab")
		)
		(fp_line
			(start -0.12065 -0.2794)
			(end 0.12065 -0.2794)
			(stroke
				(width 0.1)
				(type default)
			)
			(layer "F.Fab")
		)
		(fp_line
			(start 0.120396 0.2794)
			(end -0.12065 0.2794)
			(stroke
				(width 0.1)
				(type default)
			)
			(layer "F.Fab")
		)
		(fp_line
			(start -0.12065 0.2794)
			(end -0.12065 0.3048)
			(stroke
				(width 0.1)
				(type default)
			)
			(layer "F.Fab")
		)
		(fp_line
			(start 0.67945 0.3048)
			(end 0.120396 0.3048)
			(stroke
				(width 0.1)
				(type default)
			)
			(layer "F.Fab")
		)
		(fp_line
			(start 0.120396 0.3048)
			(end 0.120396 0.2794)
			(stroke
				(width 0.1)
				(type default)
			)
			(layer "F.Fab")
		)
		(fp_line
			(start -0.12065 0.3048)
			(end -0.67945 0.3048)
			(stroke
				(width 0.1)
				(type default)
			)
			(layer "F.Fab")
		)
		(fp_line
			(start -0.67945 0.3048)
			(end -0.67945 -0.305054)
			(stroke
				(width 0.1)
				(type default)
			)
			(layer "F.Fab")
		)
		(pad "1" smd circle
			(at -0.40005 0 90)
			(size 0 0)
			(layers "F.Cu" "F.Mask" "F.Paste")
			(net "P12V_SSD10_VIN_P")
		)
		(pad "2" smd circle
			(at 0.40005 0 90)
			(size 0 0)
			(layers "F.Cu" "F.Mask" "F.Paste")
			(net "P12V_SSD10_VIN_N")
		)
	)
	(footprint ""
		(layer "F.Cu")
		(at 189.98565 -25.1587 -90)
		(property "Reference" "R5744"
			(at 0 0 270)
			(layer "F.SilkS")
			(hide yes)
			(effects
				(font
					(size 1.27 1.27)
				)
			)
		)
		(property "Value" ""
			(at 0 0 270)
			(layer "F.Fab")
			(effects
				(font
					(size 1.27 1.27)
				)
			)
		)
		(duplicate_pad_numbers_are_jumpers no)
		(fp_line
			(start -0.7874 0.4064)
			(end -0.7874 -0.4064)
			(stroke
				(width 0.1524)
				(type default)
			)
			(layer "F.SilkS")
		)
		(fp_line
			(start 0.7874 0.4064)
			(end -0.7874 0.4064)
			(stroke
				(width 0.1524)
				(type default)
			)
			(layer "F.SilkS")
		)
		(fp_line
			(start -0.7874 -0.4064)
			(end 0.7874 -0.4064)
			(stroke
				(width 0.1524)
				(type default)
			)
			(layer "F.SilkS")
		)
		(fp_line
			(start 0.7874 -0.4064)
			(end 0.7874 0.4064)
			(stroke
				(width 0.1524)
				(type default)
			)
			(layer "F.SilkS")
		)
		(fp_line
			(start -0.67945 0.3048)
			(end -0.67945 -0.305054)
			(stroke
				(width 0.1)
				(type default)
			)
			(layer "F.Fab")
		)
		(fp_line
			(start -0.12065 0.3048)
			(end -0.67945 0.3048)
			(stroke
				(width 0.1)
				(type default)
			)
			(layer "F.Fab")
		)
		(fp_line
			(start 0.120396 0.3048)
			(end 0.120396 0.2794)
			(stroke
				(width 0.1)
				(type default)
			)
			(layer "F.Fab")
		)
		(fp_line
			(start 0.67945 0.3048)
			(end 0.120396 0.3048)
			(stroke
				(width 0.1)
				(type default)
			)
			(layer "F.Fab")
		)
		(fp_line
			(start -0.12065 0.2794)
			(end -0.12065 0.3048)
			(stroke
				(width 0.1)
				(type default)
			)
			(layer "F.Fab")
		)
		(fp_line
			(start 0.120396 0.2794)
			(end -0.12065 0.2794)
			(stroke
				(width 0.1)
				(type default)
			)
			(layer "F.Fab")
		)
		(fp_line
			(start -0.12065 -0.2794)
			(end 0.12065 -0.2794)
			(stroke
				(width 0.1)
				(type default)
			)
			(layer "F.Fab")
		)
		(fp_line
			(start 0.12065 -0.2794)
			(end 0.12065 -0.3048)
			(stroke
				(width 0.1)
				(type default)
			)
			(layer "F.Fab")
		)
		(fp_line
			(start 0.12065 -0.3048)
			(end 0.67945 -0.3048)
			(stroke
				(width 0.1)
				(type default)
			)
			(layer "F.Fab")
		)
		(fp_line
			(start 0.67945 -0.3048)
			(end 0.67945 0.3048)
			(stroke
				(width 0.1)
				(type default)
			)
			(layer "F.Fab")
		)
		(fp_line
			(start -0.67945 -0.305054)
			(end -0.12065 -0.305054)
			(stroke
				(width 0.1)
				(type default)
			)
			(layer "F.Fab")
		)
		(fp_line
			(start -0.12065 -0.305054)
			(end -0.12065 -0.2794)
			(stroke
				(width 0.1)
				(type default)
			)
			(layer "F.Fab")
		)
		(pad "1" smd circle
			(at -0.40005 0 270)
			(size 0 0)
			(layers "F.Cu" "F.Mask" "F.Paste")
			(net "SSD6_LED_ISO_N")
		)
		(pad "2" smd circle
			(at 0.40005 0 270)
			(size 0 0)
			(layers "F.Cu" "F.Mask" "F.Paste")
			(net "SSD6_LED_ISO_R_N")
		)
	)
	(footprint ""
		(layer "F.Cu")
		(at 6.196584 -13.029184 180)
		(property "Reference" "C3877"
			(at 0 0 180)
			(layer "F.SilkS")
			(hide yes)
			(effects
				(font
					(size 1.27 1.27)
				)
			)
		)
		(property "Value" ""
			(at 0 0 180)
			(layer "F.Fab")
			(effects
				(font
					(size 1.27 1.27)
				)
			)
		)
		(duplicate_pad_numbers_are_jumpers no)
		(fp_line
			(start 0.7874 0.4064)
			(end -0.7874 0.4064)
			(stroke
				(width 0.1524)
				(type default)
			)
			(layer "F.SilkS")
		)
		(fp_line
			(start 0.7874 -0.4064)
			(end 0.7874 0.4064)
			(stroke
				(width 0.1524)
				(type default)
			)
			(layer "F.SilkS")
		)
		(fp_line
			(start -0.7874 0.4064)
			(end -0.7874 -0.4064)
			(stroke
				(width 0.1524)
				(type default)
			)
			(layer "F.SilkS")
		)
		(fp_line
			(start -0.7874 -0.4064)
			(end 0.7874 -0.4064)
			(stroke
				(width 0.1524)
				(type default)
			)
			(layer "F.SilkS")
		)
		(fp_line
			(start 0.67945 0.3048)
			(end 0.120396 0.3048)
			(stroke
				(width 0.1)
				(type default)
			)
			(layer "F.Fab")
		)
		(fp_line
			(start 0.67945 -0.3048)
			(end 0.67945 0.3048)
			(stroke
				(width 0.1)
				(type default)
			)
			(layer "F.Fab")
		)
		(fp_line
			(start 0.12065 -0.2794)
			(end 0.12065 -0.3048)
			(stroke
				(width 0.1)
				(type default)
			)
			(layer "F.Fab")
		)
		(fp_line
			(start 0.12065 -0.3048)
			(end 0.67945 -0.3048)
			(stroke
				(width 0.1)
				(type default)
			)
			(layer "F.Fab")
		)
		(fp_line
			(start 0.120396 0.3048)
			(end 0.120396 0.2794)
			(stroke
				(width 0.1)
				(type default)
			)
			(layer "F.Fab")
		)
		(fp_line
			(start 0.120396 0.2794)
			(end -0.12065 0.2794)
			(stroke
				(width 0.1)
				(type default)
			)
			(layer "F.Fab")
		)
		(fp_line
			(start -0.12065 0.3048)
			(end -0.67945 0.3048)
			(stroke
				(width 0.1)
				(type default)
			)
			(layer "F.Fab")
		)
		(fp_line
			(start -0.12065 0.2794)
			(end -0.12065 0.3048)
			(stroke
				(width 0.1)
				(type default)
			)
			(layer "F.Fab")
		)
		(fp_line
			(start -0.12065 -0.2794)
			(end 0.12065 -0.2794)
			(stroke
				(width 0.1)
				(type default)
			)
			(layer "F.Fab")
		)
		(fp_line
			(start -0.12065 -0.305054)
			(end -0.12065 -0.2794)
			(stroke
				(width 0.1)
				(type default)
			)
			(layer "F.Fab")
		)
		(fp_line
			(start -0.67945 0.3048)
			(end -0.67945 -0.305054)
			(stroke
				(width 0.1)
				(type default)
			)
			(layer "F.Fab")
		)
		(fp_line
			(start -0.67945 -0.305054)
			(end -0.12065 -0.305054)
			(stroke
				(width 0.1)
				(type default)
			)
			(layer "F.Fab")
		)
		(pad "1" smd circle
			(at -0.40005 0 180)
			(size 0 0)
			(layers "F.Cu" "F.Mask" "F.Paste")
			(net "P12V_SSD0")
		)
		(pad "2" smd circle
			(at 0.40005 0 180)
			(size 0 0)
			(layers "F.Cu" "F.Mask" "F.Paste")
			(net "GND")
		)
	)
	(footprint ""
		(layer "F.Cu")
		(at 159.051752 -356.244906 90)
		(property "Reference" "C402"
			(at 0 0 90)
			(layer "F.SilkS")
			(hide yes)
			(effects
				(font
					(size 1.27 1.27)
				)
			)
		)
		(property "Value" ""
			(at 0 0 90)
			(layer "F.Fab")
			(effects
				(font
					(size 1.27 1.27)
				)
			)
		)
		(duplicate_pad_numbers_are_jumpers no)
		(fp_line
			(start 0.299974 -0.150114)
			(end 0.299974 0.150114)
			(stroke
				(width 0.1)
				(type default)
			)
			(layer "F.Fab")
		)
		(fp_line
			(start -0.299974 -0.150114)
			(end 0.299974 -0.150114)
			(stroke
				(width 0.1)
				(type default)
			)
			(layer "F.Fab")
		)
		(fp_line
			(start 0.299974 0.150114)
			(end -0.299974 0.150114)
			(stroke
				(width 0.1)
				(type default)
			)
			(layer "F.Fab")
		)
		(fp_line
			(start -0.299974 0.150114)
			(end -0.299974 -0.150114)
			(stroke
				(width 0.1)
				(type default)
			)
			(layer "F.Fab")
		)
		(pad "1" smd rect
			(at -0.2667 0 90)
			(size 0.3048 0.381)
			(layers "F.Cu" "F.Mask" "F.Paste")
			(net "P5E_PEX1_STN7_TX_DP<112>")
		)
		(pad "2" smd rect
			(at 0.2667 0 90)
			(size 0.3048 0.381)
			(layers "F.Cu" "F.Mask" "F.Paste")
			(net "P5E_PEX1_STN7_TX_C_DP<112>")
		)
	)
	(footprint ""
		(layer "F.Cu")
		(at 186.719972 -15.649956 180)
		(property "Reference" "H101"
			(at -1.124966 2.488184 0)
			(unlocked yes)
			(layer "B.SilkS")
			(effects
				(font
					(size 0.7874 0.5842)
					(thickness 0.1524)
				)
				(justify left mirror)
			)
		)
		(property "Value" ""
			(at 0 0 180)
			(layer "F.Fab")
			(effects
				(font
					(size 1.27 1.27)
				)
			)
		)
		(duplicate_pad_numbers_are_jumpers no)
		(pad "1" thru_hole rect
			(at 0 0 180)
			(size 4.2164 5.0038)
			(drill 2.0066
				(offset 0.099822 0)
			)
			(layers "*.Cu" "*.Mask")
			(remove_unused_layers no)
			(net "Net_8562")
			(clearance -0.8509)
			(padstack
				(mode front_inner_back)
				(layer "Inner"
					(shape circle)
					(size 4.0132 4.0132)
					(clearance -0.7493)
				)
				(layer "B.Cu"
					(shape circle)
					(size 4.0132 4.0132)
					(clearance -0.7493)
				)
			)
		)
	)
)
